# S9S_MB_2U (Grand Teton) — schematic netlist excerpt (pin names and nets, part order shuffled) for the footprints in the layout excerpt that follows; sources: Cadence DE-HDL packaged netlist, KiCad conversion of 03242023_DA0F0TMBIJ0_F0T_Motherboard_J_brd_V01_OCP.brd

PR4229  Q_RES  499 1% CHIP  pkg 0402LF  page 276 : A = PVCCFA_EHV_CPU0 ; B = GND
PC268_P0_6  Q_CAP  22UF 4V 20% X6S  pkg C0805  page 269 : A = PVCCIN_CPU0 ; B = GND
C1262  Q_CAP  10UF 6.3V 20% X6S  pkg C0402  page 189 : A = P1V05_PCH_PLL_AUX ; B = GND

(kicad_pcb
	(version 20260206)
	(generator "pcbnew")
	(generator_version "10.0")
	(general
		(thickness 1.6)
		(legacy_teardrops no)
	)
	(paper "A4")
	(title_block
		(title "03242023_DA0F0TMBIJ0_F0T_Motherboard_J_brd_V01_OCP.brd")
		(comment 1 "Grand Teton / footprints 5055-5057 of 6105")
	)
	(layers
		(0 "F.Cu" signal "TOP")
		(4 "In1.Cu" signal "GND")
		(6 "In2.Cu" signal "IN1")
		(8 "In3.Cu" signal "GND1")
		(10 "In4.Cu" signal "IN2")
		(12 "In5.Cu" signal "GND2")
		(14 "In6.Cu" signal "IN3")
		(16 "In7.Cu" signal "GND3")
		(18 "In8.Cu" signal "VCC")
		(20 "In9.Cu" signal "VCC1")
		(22 "In10.Cu" signal "GND4")
		(24 "In11.Cu" signal "IN4")
		(26 "In12.Cu" signal "GND5")
		(28 "In13.Cu" signal "IN5")
		(30 "In14.Cu" signal "GND6")
		(32 "In15.Cu" signal "IN6")
		(34 "In16.Cu" signal "GND7")
		(2 "B.Cu" signal "BOTTOM")
		(9 "F.Adhes" user "F.Adhesive")
		(11 "B.Adhes" user "B.Adhesive")
		(13 "F.Paste" user "Package Geometry/Pastemask Top")
		(15 "B.Paste" user "Package Geometry/Pastemask Bottom")
		(5 "F.SilkS" user "Ref Des/Silkscreen Top")
		(7 "B.SilkS" user "Ref Des/Silkscreen Bottom")
		(1 "F.Mask" user "Board Geometry/Soldermask Top")
		(3 "B.Mask" user "Board Geometry/Soldermask Bottom")
		(17 "Dwgs.User" user "User.Drawings")
		(19 "Cmts.User" user "User.Comments")
		(21 "Eco1.User" user "User.Eco1")
		(23 "Eco2.User" user "User.Eco2")
		(25 "Edge.Cuts" user "Board Geometry/Outline")
		(27 "Margin" user)
		(31 "F.CrtYd" user "Package Geometry/Place Bound Top")
		(29 "B.CrtYd" user "Package Geometry/Place Bound Bottom")
		(35 "F.Fab" user "Ref Des/Assembly Top")
		(33 "B.Fab" user "Ref Des/Assembly Bottom")
	)
	(footprint ""
		(layer "B.Cu")
		(at 339.042756 -50.678842 90)
		(property "Reference" "C1262"
			(at 0 0 90)
			(layer "B.SilkS")
			(hide yes)
			(effects
				(font
					(size 1.27 1.27)
				)
				(justify mirror)
			)
		)
		(property "Value" ""
			(at 0 0 90)
			(layer "B.Fab")
			(effects
				(font
					(size 1.27 1.27)
				)
				(justify mirror)
			)
		)
		(duplicate_pad_numbers_are_jumpers no)
		(fp_line
			(start 0.7874 -0.4064)
			(end -0.7874 -0.4064)
			(stroke
				(width 0.1524)
				(type default)
			)
			(layer "B.SilkS")
		)
		(fp_line
			(start -0.7874 -0.4064)
			(end -0.7874 0.4064)
			(stroke
				(width 0.1524)
				(type default)
			)
			(layer "B.SilkS")
		)
		(fp_line
			(start 0.7874 0.4064)
			(end 0.7874 -0.4064)
			(stroke
				(width 0.1524)
				(type default)
			)
			(layer "B.SilkS")
		)
		(fp_line
			(start -0.7874 0.4064)
			(end 0.7874 0.4064)
			(stroke
				(width 0.1524)
				(type default)
			)
			(layer "B.SilkS")
		)
		(fp_line
			(start 0.67945 -0.305054)
			(end 0.12065 -0.305054)
			(stroke
				(width 0.1)
				(type default)
			)
			(layer "B.Fab")
		)
		(fp_line
			(start 0.12065 -0.305054)
			(end 0.12065 -0.2794)
			(stroke
				(width 0.1)
				(type default)
			)
			(layer "B.Fab")
		)
		(fp_line
			(start -0.12065 -0.3048)
			(end -0.67945 -0.3048)
			(stroke
				(width 0.1)
				(type default)
			)
			(layer "B.Fab")
		)
		(fp_line
			(start -0.67945 -0.3048)
			(end -0.67945 0.3048)
			(stroke
				(width 0.1)
				(type default)
			)
			(layer "B.Fab")
		)
		(fp_line
			(start 0.12065 -0.2794)
			(end -0.12065 -0.2794)
			(stroke
				(width 0.1)
				(type default)
			)
			(layer "B.Fab")
		)
		(fp_line
			(start -0.12065 -0.2794)
			(end -0.12065 -0.3048)
			(stroke
				(width 0.1)
				(type default)
			)
			(layer "B.Fab")
		)
		(fp_line
			(start 0.12065 0.2794)
			(end 0.12065 0.3048)
			(stroke
				(width 0.1)
				(type default)
			)
			(layer "B.Fab")
		)
		(fp_line
			(start -0.120396 0.2794)
			(end 0.12065 0.2794)
			(stroke
				(width 0.1)
				(type default)
			)
			(layer "B.Fab")
		)
		(fp_line
			(start 0.67945 0.3048)
			(end 0.67945 -0.305054)
			(stroke
				(width 0.1)
				(type default)
			)
			(layer "B.Fab")
		)
		(fp_line
			(start 0.12065 0.3048)
			(end 0.67945 0.3048)
			(stroke
				(width 0.1)
				(type default)
			)
			(layer "B.Fab")
		)
		(fp_line
			(start -0.120396 0.3048)
			(end -0.120396 0.2794)
			(stroke
				(width 0.1)
				(type default)
			)
			(layer "B.Fab")
		)
		(fp_line
			(start -0.67945 0.3048)
			(end -0.120396 0.3048)
			(stroke
				(width 0.1)
				(type default)
			)
			(layer "B.Fab")
		)
		(pad "1" smd circle
			(at 0.40005 0 270)
			(size 0 0)
			(layers "B.Cu" "B.Mask" "B.Paste")
			(net "P1V05_PCH_PLL_AUX")
		)
		(pad "2" smd circle
			(at -0.40005 0 270)
			(size 0 0)
			(layers "B.Cu" "B.Mask" "B.Paste")
			(net "GND")
		)
	)
	(footprint ""
		(layer "B.Cu")
		(at 409.32608 -148.173948 180)
		(property "Reference" "PR4229"
			(at 0 0 0)
			(layer "B.SilkS")
			(hide yes)
			(effects
				(font
					(size 1.27 1.27)
				)
				(justify mirror)
			)
		)
		(property "Value" ""
			(at 0 0 0)
			(layer "B.Fab")
			(effects
				(font
					(size 1.27 1.27)
				)
				(justify mirror)
			)
		)
		(duplicate_pad_numbers_are_jumpers no)
		(fp_line
			(start 0.7874 0.4064)
			(end 0.7874 -0.4064)
			(stroke
				(width 0.1524)
				(type default)
			)
			(layer "B.SilkS")
		)
		(fp_line
			(start 0.7874 -0.4064)
			(end -0.7874 -0.4064)
			(stroke
				(width 0.1524)
				(type default)
			)
			(layer "B.SilkS")
		)
		(fp_line
			(start -0.7874 0.4064)
			(end 0.7874 0.4064)
			(stroke
				(width 0.1524)
				(type default)
			)
			(layer "B.SilkS")
		)
		(fp_line
			(start -0.7874 -0.4064)
			(end -0.7874 0.4064)
			(stroke
				(width 0.1524)
				(type default)
			)
			(layer "B.SilkS")
		)
		(fp_line
			(start 0.67945 0.3048)
			(end 0.67945 -0.305054)
			(stroke
				(width 0.1)
				(type default)
			)
			(layer "B.Fab")
		)
		(fp_line
			(start 0.67945 -0.305054)
			(end 0.12065 -0.305054)
			(stroke
				(width 0.1)
				(type default)
			)
			(layer "B.Fab")
		)
		(fp_line
			(start 0.12065 0.3048)
			(end 0.67945 0.3048)
			(stroke
				(width 0.1)
				(type default)
			)
			(layer "B.Fab")
		)
		(fp_line
			(start 0.12065 0.2794)
			(end 0.12065 0.3048)
			(stroke
				(width 0.1)
				(type default)
			)
			(layer "B.Fab")
		)
		(fp_line
			(start 0.12065 -0.2794)
			(end -0.12065 -0.2794)
			(stroke
				(width 0.1)
				(type default)
			)
			(layer "B.Fab")
		)
		(fp_line
			(start 0.12065 -0.305054)
			(end 0.12065 -0.2794)
			(stroke
				(width 0.1)
				(type default)
			)
			(layer "B.Fab")
		)
		(fp_line
			(start -0.120396 0.3048)
			(end -0.120396 0.2794)
			(stroke
				(width 0.1)
				(type default)
			)
			(layer "B.Fab")
		)
		(fp_line
			(start -0.120396 0.2794)
			(end 0.12065 0.2794)
			(stroke
				(width 0.1)
				(type default)
			)
			(layer "B.Fab")
		)
		(fp_line
			(start -0.12065 -0.2794)
			(end -0.12065 -0.3048)
			(stroke
				(width 0.1)
				(type default)
			)
			(layer "B.Fab")
		)
		(fp_line
			(start -0.12065 -0.3048)
			(end -0.67945 -0.3048)
			(stroke
				(width 0.1)
				(type default)
			)
			(layer "B.Fab")
		)
		(fp_line
			(start -0.67945 0.3048)
			(end -0.120396 0.3048)
			(stroke
				(width 0.1)
				(type default)
			)
			(layer "B.Fab")
		)
		(fp_line
			(start -0.67945 -0.3048)
			(end -0.67945 0.3048)
			(stroke
				(width 0.1)
				(type default)
			)
			(layer "B.Fab")
		)
		(pad "1" smd circle
			(at 0.40005 0)
			(size 0 0)
			(layers "B.Cu" "B.Mask" "B.Paste")
			(net "PVCCFA_EHV_CPU0")
		)
		(pad "2" smd circle
			(at -0.40005 0)
			(size 0 0)
			(layers "B.Cu" "B.Mask" "B.Paste")
			(net "GND")
		)
	)
	(footprint ""
		(layer "B.Cu")
		(at 333.382366 -328.298048 -90)
		(property "Reference" "PC268_P0_6"
			(at 0 0 90)
			(layer "B.SilkS")
			(hide yes)
			(effects
				(font
					(size 1.27 1.27)
				)
				(justify mirror)
			)
		)
		(property "Value" ""
			(at 0 0 90)
			(layer "B.Fab")
			(effects
				(font
					(size 1.27 1.27)
				)
				(justify mirror)
			)
		)
		(duplicate_pad_numbers_are_jumpers no)
		(fp_line
			(start -1.524 0.762)
			(end 1.524 0.762)
			(stroke
				(width 0.1524)
				(type default)
			)
			(layer "B.SilkS")
		)
		(fp_line
			(start 1.524 0.762)
			(end 1.524 -0.762)
			(stroke
				(width 0.1524)
				(type default)
			)
			(layer "B.SilkS")
		)
		(fp_line
			(start -1.524 -0.762)
			(end -1.524 0.762)
			(stroke
				(width 0.1524)
				(type default)
			)
			(layer "B.SilkS")
		)
		(fp_line
			(start 1.524 -0.762)
			(end -1.524 -0.762)
			(stroke
				(width 0.1524)
				(type default)
			)
			(layer "B.SilkS")
		)
		(fp_line
			(start -1.1049 0.724916)
			(end -1.1049 -0.724916)
			(stroke
				(width 0.1)
				(type default)
			)
			(layer "B.Fab")
		)
		(fp_line
			(start 1.1049 0.724916)
			(end -1.1049 0.724916)
			(stroke
				(width 0.1)
				(type default)
			)
			(layer "B.Fab")
		)
		(fp_line
			(start -1.1049 -0.724916)
			(end 1.1049 -0.724916)
			(stroke
				(width 0.1)
				(type default)
			)
			(layer "B.Fab")
		)
		(fp_line
			(start 1.1049 -0.724916)
			(end 1.1049 0.724916)
			(stroke
				(width 0.1)
				(type default)
			)
			(layer "B.Fab")
		)
		(pad "1" smd rect
			(at 0.889 0 270)
			(size 1.016 1.27)
			(layers "B.Cu" "B.Mask" "B.Paste")
			(net "PVCCIN_CPU0")
		)
		(pad "2" smd rect
			(at -0.889 0 270)
			(size 1.016 1.27)
			(layers "B.Cu" "B.Mask" "B.Paste")
			(net "GND")
		)
	)
)
